(kicad_pcb
	(version 20260206)
	(generator "pcbnew")
	(generator_version "10.0")
	(general
		(thickness 1.21888)
		(legacy_teardrops no)
	)
	(paper "A4")
	(title_block
		(title "timecard-proto-v0 — Timingcard_PCB.PcbDoc")
		(comment 1 "Time Appliance Project (Time Card) / footprints 147-160 of 167")
	)
	(layers
		(0 "F.Cu" signal "TOP")
		(4 "In1.Cu" signal "SGND")
		(6 "In2.Cu" signal "IN1")
		(8 "In3.Cu" signal "IN2")
		(10 "In4.Cu" signal "SGND1")
		(2 "B.Cu" signal "BOTTOM")
		(9 "F.Adhes" user "F.Adhesive")
		(11 "B.Adhes" user "B.Adhesive")
		(13 "F.Paste" user "Top Paste")
		(15 "B.Paste" user "Bottom Paste")
		(5 "F.SilkS" user "Top Overlay")
		(7 "B.SilkS" user "Bottom Overlay")
		(1 "F.Mask" user "Top Solder")
		(3 "B.Mask" user "Bottom Solder")
		(17 "Dwgs.User" user "User.Drawings")
		(19 "Cmts.User" user "User.Comments")
		(21 "Eco1.User" user "User.Eco1")
		(23 "Eco2.User" user "User.Eco2")
		(25 "Edge.Cuts" user)
		(27 "Margin" user)
		(31 "F.CrtYd" user "Top Courtyard")
		(29 "B.CrtYd" user "Bottom Courtyard")
		(35 "F.Fab" user "Top Component Center")
		(33 "B.Fab" user "Bottom Component Center")
	)
	(footprint "Connectors:AMPHENOL-901-143-6RFX"
		(layer "F.Cu")
		(at 63.564595 97.5596 180)
		(property "Reference" "AN1"
			(at -5.24553 -4.652455 0)
			(unlocked yes)
			(layer "F.SilkS")
			(effects
				(font
					(size 0.762 0.762)
					(thickness 0.2286)
				)
				(justify left bottom)
			)
		)
		(property "Value" "RF-901-143-6FRX"
			(at 4.6101 -12.21359 0)
			(unlocked yes)
			(layer "F.SilkS")
			(hide yes)
			(effects
				(font
					(size 1.524 1.524)
					(thickness 0.254)
				)
				(justify left bottom)
			)
		)
		(sheetfile ".kicad_sch")
		(duplicate_pad_numbers_are_jumpers no)
		(fp_line
			(start 4.318 3.556)
			(end 3.302 4.572)
			(stroke
				(width 0.1778)
				(type solid)
			)
			(layer "F.SilkS")
		)
		(fp_line
			(start 4.318 -3.556)
			(end 3.302 -4.572)
			(stroke
				(width 0.1778)
				(type solid)
			)
			(layer "F.SilkS")
		)
		(fp_line
			(start 3.302 4.572)
			(end 2.54 4.572)
			(stroke
				(width 0.1778)
				(type solid)
			)
			(layer "F.SilkS")
		)
		(fp_line
			(start 3.302 -4.572)
			(end 2.54 -4.572)
			(stroke
				(width 0.1778)
				(type solid)
			)
			(layer "F.SilkS")
		)
		(fp_line
			(start 2.54 4.572)
			(end -4.572 4.572)
			(stroke
				(width 0.1778)
				(type solid)
			)
			(layer "F.SilkS")
		)
		(fp_line
			(start 2.54 -4.572)
			(end -4.572 -4.572)
			(stroke
				(width 0.1778)
				(type solid)
			)
			(layer "F.SilkS")
		)
		(fp_line
			(start -4.572 2.54)
			(end -4.572 4.572)
			(stroke
				(width 0.1778)
				(type solid)
			)
			(layer "F.SilkS")
		)
		(fp_line
			(start -4.572 -4.572)
			(end -4.572 -2.54)
			(stroke
				(width 0.1778)
				(type solid)
			)
			(layer "F.SilkS")
		)
		(pad "1" thru_hole circle
			(at 0 0 180)
			(size 2.8448 2.8448)
			(drill 1.524)
			(layers "*.Cu" "*.Mask")
			(remove_unused_layers no)
			(net "ANT1")
			(thermal_bridge_angle 90)
		)
		(pad "2" thru_hole circle
			(at -2.54 2.54 180)
			(size 3.048 3.048)
			(drill 1.7272)
			(layers "*.Cu" "*.Mask")
			(remove_unused_layers no)
			(net "GND")
			(thermal_bridge_angle 90)
		)
		(pad "3" thru_hole circle
			(at -2.54 -2.54 180)
			(size 3.048 3.048)
			(drill 1.7272)
			(layers "*.Cu" "*.Mask")
			(remove_unused_layers no)
			(net "GND")
			(thermal_bridge_angle 90)
		)
		(pad "4" thru_hole circle
			(at 2.54 -2.54 180)
			(size 3.048 3.048)
			(drill 1.7272)
			(layers "*.Cu" "*.Mask")
			(remove_unused_layers no)
			(net "GND")
			(thermal_bridge_angle 90)
		)
		(pad "5" thru_hole circle
			(at 2.54 2.54 180)
			(size 3.048 3.048)
			(drill 1.7272)
			(layers "*.Cu" "*.Mask")
			(remove_unused_layers no)
			(net "GND")
			(thermal_bridge_angle 90)
		)
	)
	(footprint "Vault:CAPC1608X87X45ML20T05"
		(layer "F.Cu")
		(at 219.588595 90.9786 180)
		(property "Reference" "C9"
			(at 4.2 -0.493345 0)
			(unlocked yes)
			(layer "F.SilkS")
			(effects
				(font
					(size 0.762 0.762)
					(thickness 0.2286)
				)
				(justify left bottom)
			)
		)
		(property "Value" "0.1uF"
			(at -10.9347 -6.32079 0)
			(unlocked yes)
			(layer "F.SilkS")
			(hide yes)
			(effects
				(font
					(size 1.524 1.524)
					(thickness 0.254)
				)
				(justify left bottom)
			)
		)
		(sheetname "POWER")
		(sheetfile "POWER.kicad_sch")
		(duplicate_pad_numbers_are_jumpers no)
		(pad "1" smd rect
			(at -0.7 0 270)
			(size 1.1 1.05)
			(layers "F.Cu" "F.Mask" "F.Paste")
			(net "GND")
		)
		(pad "2" smd rect
			(at 0.7 0 270)
			(size 1.1 1.05)
			(layers "F.Cu" "F.Mask" "F.Paste")
			(net "+3.3V")
		)
	)
	(footprint "Miscellaneous Devices:J1-0603"
		(layer "F.Cu")
		(at 82.288595 129.6786 180)
		(property "Reference" "R31"
			(at -1.6 -0.493345 0)
			(unlocked yes)
			(layer "F.SilkS")
			(effects
				(font
					(size 0.762 0.762)
					(thickness 0.2286)
				)
				(justify left bottom)
			)
		)
		(property "Value" "MAC10M"
			(at 0.4445 -3.72999 0)
			(unlocked yes)
			(layer "F.SilkS")
			(hide yes)
			(effects
				(font
					(size 1.524 1.524)
					(thickness 0.254)
				)
				(justify left bottom)
			)
		)
		(sheetname "USER_IO")
		(sheetfile "USER_IO.kicad_sch")
		(duplicate_pad_numbers_are_jumpers no)
		(fp_line
			(start 0.2 0.35)
			(end -0.2 0.35)
			(stroke
				(width 0.2)
				(type solid)
			)
			(layer "F.SilkS")
		)
		(fp_line
			(start 0.2 -0.35)
			(end -0.2 -0.35)
			(stroke
				(width 0.2)
				(type solid)
			)
			(layer "F.SilkS")
		)
		(pad "1" smd rect
			(at -0.75 0 270)
			(size 0.9 0.7)
			(layers "F.Cu" "F.Mask" "F.Paste")
			(net "MAC_10Mout")
		)
		(pad "2" smd rect
			(at 0.75 0 270)
			(size 0.9 0.7)
			(layers "F.Cu" "F.Mask" "F.Paste")
			(net "ANT3")
		)
	)
	(footprint "Vault:CAPC1608X87X45ML20T05"
		(layer "F.Cu")
		(at 127.588595 69.8786 90)
		(property "Reference" "C61"
			(at -4.8 1.893345 90)
			(unlocked yes)
			(layer "F.SilkS")
			(effects
				(font
					(size 0.762 0.762)
					(thickness 0.2286)
				)
				(justify left bottom)
			)
		)
		(property "Value" "0.1uF"
			(at -3.47599 -0.2921 0)
			(unlocked yes)
			(layer "F.SilkS")
			(hide yes)
			(effects
				(font
					(size 1.524 1.524)
					(thickness 0.254)
				)
				(justify left bottom)
			)
		)
		(sheetname "GPS_IMU_SENSORS")
		(sheetfile "GPS_IMU_SENSORS.kicad_sch")
		(duplicate_pad_numbers_are_jumpers no)
		(pad "1" smd rect
			(at -0.7 0 180)
			(size 1.1 1.05)
			(layers "F.Cu" "F.Mask" "F.Paste")
			(net "GND")
		)
		(pad "2" smd rect
			(at 0.7 0 180)
			(size 1.1 1.05)
			(layers "F.Cu" "F.Mask" "F.Paste")
			(net "+5.0V")
		)
	)
	(footprint "Connectors:AMPHENOL-901-143-6RFX"
		(layer "F.Cu")
		(at 63.564595 110.8946 180)
		(property "Reference" "AN2"
			(at -5.20749 -4.677855 0)
			(unlocked yes)
			(layer "F.SilkS")
			(effects
				(font
					(size 0.762 0.762)
					(thickness 0.2286)
				)
				(justify left bottom)
			)
		)
		(property "Value" "RF-901-143-6FRX"
			(at 4.6101 -2.05359 0)
			(unlocked yes)
			(layer "F.SilkS")
			(hide yes)
			(effects
				(font
					(size 1.524 1.524)
					(thickness 0.254)
				)
				(justify left bottom)
			)
		)
		(sheetfile ".kicad_sch")
		(duplicate_pad_numbers_are_jumpers no)
		(fp_line
			(start 4.318 3.556)
			(end 3.302 4.572)
			(stroke
				(width 0.1778)
				(type solid)
			)
			(layer "F.SilkS")
		)
		(fp_line
			(start 4.318 -3.556)
			(end 3.302 -4.572)
			(stroke
				(width 0.1778)
				(type solid)
			)
			(layer "F.SilkS")
		)
		(fp_line
			(start 3.302 4.572)
			(end 2.54 4.572)
			(stroke
				(width 0.1778)
				(type solid)
			)
			(layer "F.SilkS")
		)
		(fp_line
			(start 3.302 -4.572)
			(end 2.54 -4.572)
			(stroke
				(width 0.1778)
				(type solid)
			)
			(layer "F.SilkS")
		)
		(fp_line
			(start 2.54 4.572)
			(end -4.572 4.572)
			(stroke
				(width 0.1778)
				(type solid)
			)
			(layer "F.SilkS")
		)
		(fp_line
			(start 2.54 -4.572)
			(end -4.572 -4.572)
			(stroke
				(width 0.1778)
				(type solid)
			)
			(layer "F.SilkS")
		)
		(fp_line
			(start -4.572 2.54)
			(end -4.572 4.572)
			(stroke
				(width 0.1778)
				(type solid)
			)
			(layer "F.SilkS")
		)
		(fp_line
			(start -4.572 -4.572)
			(end -4.572 -2.54)
			(stroke
				(width 0.1778)
				(type solid)
			)
			(layer "F.SilkS")
		)
		(pad "1" thru_hole circle
			(at 0 0 180)
			(size 2.8448 2.8448)
			(drill 1.524)
			(layers "*.Cu" "*.Mask")
			(remove_unused_layers no)
			(net "ANT2")
			(thermal_bridge_angle 90)
		)
		(pad "2" thru_hole circle
			(at -2.54 2.54 180)
			(size 3.048 3.048)
			(drill 1.7272)
			(layers "*.Cu" "*.Mask")
			(remove_unused_layers no)
			(net "GND")
			(thermal_bridge_angle 90)
		)
		(pad "3" thru_hole circle
			(at -2.54 -2.54 180)
			(size 3.048 3.048)
			(drill 1.7272)
			(layers "*.Cu" "*.Mask")
			(remove_unused_layers no)
			(net "GND")
			(thermal_bridge_angle 90)
		)
		(pad "4" thru_hole circle
			(at 2.54 -2.54 180)
			(size 3.048 3.048)
			(drill 1.7272)
			(layers "*.Cu" "*.Mask")
			(remove_unused_layers no)
			(net "GND")
			(thermal_bridge_angle 90)
		)
		(pad "5" thru_hole circle
			(at 2.54 2.54 180)
			(size 3.048 3.048)
			(drill 1.7272)
			(layers "*.Cu" "*.Mask")
			(remove_unused_layers no)
			(net "GND")
			(thermal_bridge_angle 90)
		)
	)
	(footprint "Vault:CAPC1608X87X45ML20T05"
		(layer "F.Cu")
		(at 219.588595 96.1786 180)
		(property "Reference" "C10"
			(at 4.1 1.006655 0)
			(unlocked yes)
			(layer "F.SilkS")
			(effects
				(font
					(size 0.762 0.762)
					(thickness 0.2286)
				)
				(justify left bottom)
			)
		)
		(property "Value" "0.1uF"
			(at -9.9949 -0.30099 0)
			(unlocked yes)
			(layer "F.SilkS")
			(hide yes)
			(effects
				(font
					(size 1.524 1.524)
					(thickness 0.254)
				)
				(justify left bottom)
			)
		)
		(sheetname "POWER")
		(sheetfile "POWER.kicad_sch")
		(duplicate_pad_numbers_are_jumpers no)
		(pad "1" smd rect
			(at -0.7 0 270)
			(size 1.1 1.05)
			(layers "F.Cu" "F.Mask" "F.Paste")
			(net "GND")
		)
		(pad "2" smd rect
			(at 0.7 0 270)
			(size 1.1 1.05)
			(layers "F.Cu" "F.Mask" "F.Paste")
			(net "+3.3V")
		)
	)
	(footprint "Capacitors:CAPC2012X14N"
		(layer "B.Cu")
		(at 118.504795 85.7994)
		(property "Reference" "C87"
			(at -2.1412 0.622545 0)
			(unlocked yes)
			(layer "B.SilkS")
			(effects
				(font
					(size 0.762 0.762)
					(thickness 0.254)
				)
				(justify left bottom mirror)
			)
		)
		(property "Value" "CAP_0805_10UF_25V"
			(at 1.5875 3.52679 0)
			(unlocked yes)
			(layer "B.SilkS")
			(hide yes)
			(effects
				(font
					(size 1.524 1.524)
					(thickness 0.254)
				)
				(justify left bottom mirror)
			)
		)
		(sheetname "GPS_IMU_SENSORS")
		(sheetfile "GPS_IMU_SENSORS.kicad_sch")
		(duplicate_pad_numbers_are_jumpers no)
		(fp_line
			(start -0.762 -0.9652)
			(end 0.762 -0.9652)
			(stroke
				(width 0.1524)
				(type solid)
			)
			(layer "B.SilkS")
		)
		(fp_line
			(start -0.762 0.9652)
			(end 0.762 0.9652)
			(stroke
				(width 0.1524)
				(type solid)
			)
			(layer "B.SilkS")
		)
		(pad "1" smd rect
			(at -0.9 0 270)
			(size 1.45 1.15)
			(layers "B.Cu" "B.Mask" "B.Paste")
			(net "+3.3V")
		)
		(pad "2" smd rect
			(at 0.9 0 270)
			(size 1.45 1.15)
			(layers "B.Cu" "B.Mask" "B.Paste")
			(net "GND")
		)
	)
	(footprint "Vault:CAPC1608X87X45ML20T05"
		(layer "B.Cu")
		(at 118.657195 88.0854 180)
		(property "Reference" "C88"
			(at 2.2686 -0.586545 0)
			(unlocked yes)
			(layer "B.SilkS")
			(effects
				(font
					(size 0.762 0.762)
					(thickness 0.254)
				)
				(justify left bottom mirror)
			)
		)
		(property "Value" "0.1uF"
			(at -3.47599 0.2921 90)
			(unlocked yes)
			(layer "B.SilkS")
			(hide yes)
			(effects
				(font
					(size 1.524 1.524)
					(thickness 0.254)
				)
				(justify left bottom mirror)
			)
		)
		(sheetname "GPS_IMU_SENSORS")
		(sheetfile "GPS_IMU_SENSORS.kicad_sch")
		(duplicate_pad_numbers_are_jumpers no)
		(pad "1" smd rect
			(at -0.7 0 90)
			(size 1.1 1.05)
			(layers "B.Cu" "B.Mask" "B.Paste")
			(net "GND")
		)
		(pad "2" smd rect
			(at 0.7 0 90)
			(size 1.1 1.05)
			(layers "B.Cu" "B.Mask" "B.Paste")
			(net "+3.3V")
		)
	)
	(footprint "Capacitors:CAPC1005X06N"
		(layer "B.Cu")
		(at 134.176595 151.7886 90)
		(property "Reference" "C52"
			(at 2.41349 -0.613855 270)
			(unlocked yes)
			(layer "B.SilkS")
			(effects
				(font
					(size 0.762 0.762)
					(thickness 0.254)
				)
				(justify left bottom mirror)
			)
		)
		(property "Value" "CAP_0402_0.1UF_50V"
			(at -3.47599 0.2921 0)
			(unlocked yes)
			(layer "B.SilkS")
			(hide yes)
			(effects
				(font
					(size 1.524 1.524)
					(thickness 0.254)
				)
				(justify left bottom mirror)
			)
		)
		(sheetname "PCIe_JTAG")
		(sheetfile "PCIe_JTAG.kicad_sch")
		(duplicate_pad_numbers_are_jumpers no)
		(pad "1" smd rect
			(at -0.43 0)
			(size 0.64 0.68)
			(layers "B.Cu" "B.Mask" "B.Paste")
			(net "NetC52_1")
		)
		(pad "2" smd rect
			(at 0.43 0)
			(size 0.64 0.68)
			(layers "B.Cu" "B.Mask" "B.Paste")
			(net "PCIE_TX3_P")
		)
	)
	(footprint "Capacitors:CAPC1005X06N"
		(layer "B.Cu")
		(at 126.175595 151.7886 90)
		(property "Reference" "C48"
			(at 2.41349 -0.867855 270)
			(unlocked yes)
			(layer "B.SilkS")
			(effects
				(font
					(size 0.762 0.762)
					(thickness 0.254)
				)
				(justify left bottom mirror)
			)
		)
		(property "Value" "CAP_0402_0.1UF_50V"
			(at -3.47599 0.2921 0)
			(unlocked yes)
			(layer "B.SilkS")
			(hide yes)
			(effects
				(font
					(size 1.524 1.524)
					(thickness 0.254)
				)
				(justify left bottom mirror)
			)
		)
		(sheetname "PCIe_JTAG")
		(sheetfile "PCIe_JTAG.kicad_sch")
		(duplicate_pad_numbers_are_jumpers no)
		(pad "1" smd rect
			(at -0.43 0)
			(size 0.64 0.68)
			(layers "B.Cu" "B.Mask" "B.Paste")
			(net "NetC48_1")
		)
		(pad "2" smd rect
			(at 0.43 0)
			(size 0.64 0.68)
			(layers "B.Cu" "B.Mask" "B.Paste")
			(net "PCIE_TX1_P")
		)
	)
	(footprint "Modules:RCB-F9T"
		(layer "B.Cu")
		(at 126.126095 59.8204 -90)
		(property "Reference" "U14"
			(at -0.800855 0.1283 0)
			(unlocked yes)
			(layer "B.SilkS")
			(effects
				(font
					(size 0.762 0.762)
					(thickness 0.254)
				)
				(justify left bottom mirror)
			)
		)
		(property "Value" "RCB-F9T"
			(at 28.38949 -9.0232 0)
			(unlocked yes)
			(layer "B.SilkS")
			(hide yes)
			(effects
				(font
					(size 1.524 1.524)
					(thickness 0.254)
				)
				(justify left bottom mirror)
			)
		)
		(sheetname "GPS_IMU_SENSORS")
		(sheetfile "GPS_IMU_SENSORS.kicad_sch")
		(duplicate_pad_numbers_are_jumpers no)
		(fp_line
			(start 0 67.18)
			(end 0 0)
			(stroke
				(width 0.254)
				(type solid)
			)
			(layer "B.SilkS")
		)
		(fp_line
			(start 31.75 67.18)
			(end 0 67.18)
			(stroke
				(width 0.254)
				(type solid)
			)
			(layer "B.SilkS")
		)
		(fp_line
			(start 31.75 67.18)
			(end 31.75 0)
			(stroke
				(width 0.254)
				(type solid)
			)
			(layer "B.SilkS")
		)
		(fp_line
			(start 31.75 0)
			(end 0 0)
			(stroke
				(width 0.254)
				(type solid)
			)
			(layer "B.SilkS")
		)
		(fp_circle
			(center 28.875 63.84)
			(end 27.325 63.84)
			(stroke
				(width 0.254)
				(type solid)
			)
			(fill no)
			(layer "B.SilkS")
		)
		(fp_circle
			(center 2.875 3.34)
			(end 1.325 3.34)
			(stroke
				(width 0.254)
				(type solid)
			)
			(fill no)
			(layer "B.SilkS")
		)
		(fp_circle
			(center 28.875 3.34)
			(end 27.325 3.34)
			(stroke
				(width 0.254)
				(type solid)
			)
			(fill no)
			(layer "B.SilkS")
		)
		(pad "0" thru_hole circle
			(at 18.47 6.11 270)
			(size 0 0)
			(drill 0.76)
			(layers "*.Cu" "*.Mask")
			(remove_unused_layers no)
			(thermal_bridge_angle 90)
		)
		(pad "0" thru_hole circle
			(at 22.47 6.11 270)
			(size 0 0)
			(drill 0.76)
			(layers "*.Cu" "*.Mask")
			(remove_unused_layers no)
			(thermal_bridge_angle 90)
		)
		(pad "1" smd rect
			(at 23.47 3.8875 270)
			(size 1.12 2.105)
			(layers "B.Cu" "B.Mask" "B.Paste")
			(net "+5.0V")
		)
		(pad "2" smd rect
			(at 23.47 8.3325 270)
			(size 1.12 2.105)
			(layers "B.Cu" "B.Mask" "B.Paste")
			(net "+3.3V")
		)
		(pad "3" smd rect
			(at 21.47 3.8875 270)
			(size 1.12 2.105)
			(layers "B.Cu" "B.Mask" "B.Paste")
			(net "GPS2_TX")
		)
		(pad "4" smd rect
			(at 21.47 8.3325 270)
			(size 1.12 2.105)
			(layers "B.Cu" "B.Mask" "B.Paste")
			(net "GPS2_RST")
		)
		(pad "5" smd rect
			(at 19.47 3.8875 270)
			(size 1.12 2.105)
			(layers "B.Cu" "B.Mask" "B.Paste")
			(net "GPS2_RX")
		)
		(pad "6" smd rect
			(at 19.47 8.3325 270)
			(size 1.12 2.105)
			(layers "B.Cu" "B.Mask" "B.Paste")
			(net "GPS2_TP1")
		)
		(pad "7" smd rect
			(at 17.47 3.8875 270)
			(size 1.12 2.105)
			(layers "B.Cu" "B.Mask" "B.Paste")
			(net "GPS2_TP2")
		)
		(pad "8" smd rect
			(at 17.47 8.3325 270)
			(size 1.12 2.105)
			(layers "B.Cu" "B.Mask" "B.Paste")
			(net "GND")
		)
	)
	(footprint "Capacitors:CAPC2012X14N"
		(layer "B.Cu")
		(at 125.362795 84.1992 -90)
		(property "Reference" "C89"
			(at -1.8706 0.817545 270)
			(unlocked yes)
			(layer "B.SilkS")
			(effects
				(font
					(size 0.762 0.762)
					(thickness 0.254)
				)
				(justify left bottom mirror)
			)
		)
		(property "Value" "CAP_0805_10UF_25V"
			(at 3.52679 -1.5875 0)
			(unlocked yes)
			(layer "B.SilkS")
			(hide yes)
			(effects
				(font
					(size 1.524 1.524)
					(thickness 0.254)
				)
				(justify left bottom mirror)
			)
		)
		(sheetname "GPS_IMU_SENSORS")
		(sheetfile "GPS_IMU_SENSORS.kicad_sch")
		(duplicate_pad_numbers_are_jumpers no)
		(fp_line
			(start 0.762 0.9652)
			(end -0.762 0.9652)
			(stroke
				(width 0.1524)
				(type solid)
			)
			(layer "B.SilkS")
		)
		(fp_line
			(start 0.762 -0.9652)
			(end -0.762 -0.9652)
			(stroke
				(width 0.1524)
				(type solid)
			)
			(layer "B.SilkS")
		)
		(pad "1" smd rect
			(at -0.9 0 180)
			(size 1.45 1.15)
			(layers "B.Cu" "B.Mask" "B.Paste")
			(net "+5.0V")
		)
		(pad "2" smd rect
			(at 0.9 0 180)
			(size 1.45 1.15)
			(layers "B.Cu" "B.Mask" "B.Paste")
			(net "GND")
		)
	)
	(footprint "Capacitors:CAPC1005X06N"
		(layer "B.Cu")
		(at 130.112595 151.7886 90)
		(property "Reference" "C50"
			(at 2.41349 -0.766255 270)
			(unlocked yes)
			(layer "B.SilkS")
			(effects
				(font
					(size 0.762 0.762)
					(thickness 0.254)
				)
				(justify left bottom mirror)
			)
		)
		(property "Value" "CAP_0402_0.1UF_50V"
			(at -3.47599 0.2921 0)
			(unlocked yes)
			(layer "B.SilkS")
			(hide yes)
			(effects
				(font
					(size 1.524 1.524)
					(thickness 0.254)
				)
				(justify left bottom mirror)
			)
		)
		(sheetname "PCIe_JTAG")
		(sheetfile "PCIe_JTAG.kicad_sch")
		(duplicate_pad_numbers_are_jumpers no)
		(pad "1" smd rect
			(at -0.43 0)
			(size 0.64 0.68)
			(layers "B.Cu" "B.Mask" "B.Paste")
			(net "NetC50_1")
		)
		(pad "2" smd rect
			(at 0.43 0)
			(size 0.64 0.68)
			(layers "B.Cu" "B.Mask" "B.Paste")
			(net "PCIE_TX2_P")
		)
	)
	(footprint "Capacitors:CAPC1005X06N"
		(layer "B.Cu")
		(at 127.191595 151.7886 90)
		(property "Reference" "C49"
			(at 2.41349 -0.156655 270)
			(unlocked yes)
			(layer "B.SilkS")
			(effects
				(font
					(size 0.762 0.762)
					(thickness 0.254)
				)
				(justify left bottom mirror)
			)
		)
		(property "Value" "CAP_0402_0.1UF_50V"
			(at -3.47599 0.2921 0)
			(unlocked yes)
			(layer "B.SilkS")
			(hide yes)
			(effects
				(font
					(size 1.524 1.524)
					(thickness 0.254)
				)
				(justify left bottom mirror)
			)
		)
		(sheetname "PCIe_JTAG")
		(sheetfile "PCIe_JTAG.kicad_sch")
		(duplicate_pad_numbers_are_jumpers no)
		(pad "1" smd rect
			(at -0.43 0)
			(size 0.64 0.68)
			(layers "B.Cu" "B.Mask" "B.Paste")
			(net "NetC49_1")
		)
		(pad "2" smd rect
			(at 0.43 0)
			(size 0.64 0.68)
			(layers "B.Cu" "B.Mask" "B.Paste")
			(net "PCIE_TX1_N")
		)
	)
)
